(kicad_pcb
	(version 20241229)
	(generator "pcbnew")
	(generator_version "9.0")
	(general
		(thickness 1.6642)
		(legacy_teardrops no)
	)
	(paper "A3")
	(title_block
		(title "PolarFire SoM")
		(date "2025-07-22")
		(rev "1.1.4")
		(company "Antmicro Ltd")
		(comment 1 "www.antmicro.com")
		(comment 9 "footprints 122-125 of 470")
	)
	(layers
		(0 "F.Cu" mixed)
		(4 "In1.Cu" power)
		(6 "In2.Cu" signal)
		(8 "In3.Cu" power)
		(10 "In4.Cu" signal)
		(12 "In5.Cu" power)
		(14 "In6.Cu" power)
		(16 "In7.Cu" signal)
		(18 "In8.Cu" power)
		(20 "In9.Cu" signal)
		(22 "In10.Cu" power)
		(24 "In11.Cu" signal)
		(26 "In12.Cu" signal)
		(2 "B.Cu" mixed)
		(9 "F.Adhes" user "F.Adhesive")
		(11 "B.Adhes" user "B.Adhesive")
		(13 "F.Paste" user)
		(15 "B.Paste" user)
		(5 "F.SilkS" user "F.Silkscreen")
		(7 "B.SilkS" user "B.Silkscreen")
		(1 "F.Mask" user)
		(3 "B.Mask" user)
		(17 "Dwgs.User" user "User.Drawings")
		(19 "Cmts.User" user "User.Comments")
		(21 "Eco1.User" user "User.Eco1")
		(23 "Eco2.User" user "User.Eco2")
		(25 "Edge.Cuts" user)
		(27 "Margin" user)
		(31 "F.CrtYd" user "F.Courtyard")
		(29 "B.CrtYd" user "B.Courtyard")
		(35 "F.Fab" user)
		(33 "B.Fab" user)
	)
	(footprint "antmicro-footprints:C_0402_1005Metric"
		(layer "F.Cu")
		(at 188.684904 147.897281 -90)
		(descr "Capacitor SMD 0402")
		(tags "capacitor SMD 0402")
		(property "Reference" "C98"
			(at 2.062719 -4.315096 180)
			(layer "F.SilkS")
			(effects
				(font
					(size 0.7 0.7)
					(thickness 0.15)
				)
				(justify right bottom)
			)
		)
		(property "Value" "C_22u_0402"
			(at -1.022927 2.155213 90)
			(layer "F.Fab")
			(hide yes)
			(effects
				(font
					(size 0.7 0.7)
					(thickness 0.15)
				)
				(justify right bottom)
			)
		)
		(property "Datasheet" "https://www.murata.com/products/productdetail?partno=GRM158R60J226ME01%23"
			(at 0 0 270)
			(layer "F.Fab")
			(hide yes)
			(effects
				(font
					(size 1.27 1.27)
					(thickness 0.15)
				)
			)
		)
		(property "Description" "SMD Multilayer Ceramic Capacitor, 22 uF, 4 V, 0402 [1005 Metric], X6S"
			(at 0 0 270)
			(layer "F.Fab")
			(hide yes)
			(effects
				(font
					(size 1.27 1.27)
					(thickness 0.15)
				)
			)
		)
		(property "Author" "Antmicro"
			(at 40.787623 336.582185 0)
			(layer "F.Fab")
			(hide yes)
			(effects
				(font
					(size 1 1)
					(thickness 0.15)
				)
			)
		)
		(property "Dielectric" ""
			(at 40.787623 336.582185 0)
			(layer "F.Fab")
			(hide yes)
			(effects
				(font
					(size 1 1)
					(thickness 0.15)
				)
			)
		)
		(property "License" "Apache-2.0"
			(at 40.787623 336.582185 0)
			(layer "F.Fab")
			(hide yes)
			(effects
				(font
					(size 1 1)
					(thickness 0.15)
				)
			)
		)
		(property "MPN" "GRM158R60J226ME01D"
			(at 40.787623 336.582185 0)
			(layer "F.Fab")
			(hide yes)
			(effects
				(font
					(size 1 1)
					(thickness 0.15)
				)
			)
		)
		(property "Manufacturer" "Murata"
			(at 40.787623 336.582185 0)
			(layer "F.Fab")
			(hide yes)
			(effects
				(font
					(size 1 1)
					(thickness 0.15)
				)
			)
		)
		(property "Public" ""
			(at 40.787623 336.582185 0)
			(layer "F.Fab")
			(hide yes)
			(effects
				(font
					(size 1 1)
					(thickness 0.15)
				)
			)
		)
		(property "Val" "22u"
			(at 40.787623 336.582185 0)
			(layer "F.Fab")
			(hide yes)
			(effects
				(font
					(size 1 1)
					(thickness 0.15)
				)
			)
		)
		(property "Voltage" ""
			(at 40.787623 336.582185 0)
			(layer "F.Fab")
			(hide yes)
			(effects
				(font
					(size 1 1)
					(thickness 0.15)
				)
			)
		)
		(sheetname "/Supply/")
		(sheetfile "supply.kicad_sch")
		(attr smd)
		(fp_rect
			(start -0.925 -0.47)
			(end 0.925 0.47)
			(stroke
				(width 0.05)
				(type default)
			)
			(fill no)
			(layer "F.CrtYd")
		)
		(fp_line
			(start -0.494 0.248)
			(end -0.494 -0.25)
			(stroke
				(width 0.15)
				(type solid)
			)
			(layer "F.Fab")
		)
		(fp_line
			(start 0.504 0.248)
			(end -0.494 0.248)
			(stroke
				(width 0.15)
				(type solid)
			)
			(layer "F.Fab")
		)
		(fp_line
			(start -0.494 -0.25)
			(end 0.504 -0.25)
			(stroke
				(width 0.15)
				(type solid)
			)
			(layer "F.Fab")
		)
		(fp_line
			(start 0.504 -0.25)
			(end 0.504 0.248)
			(stroke
				(width 0.15)
				(type solid)
			)
			(layer "F.Fab")
		)
		(fp_text user "${REFERENCE}"
			(at -0.939 4.599 270)
			(layer "F.Fab")
			(effects
				(font
					(size 0.7 0.7)
					(thickness 0.15)
				)
				(justify left bottom)
			)
		)
		(fp_text user "License: Apache-2.0"
			(at -0.939 5.799 270)
			(layer "F.Fab")
			(effects
				(font
					(size 0.7 0.7)
					(thickness 0.15)
				)
				(justify left bottom)
			)
		)
		(fp_text user "Author: Antmicro"
			(at -0.939 3.399 270)
			(layer "F.Fab")
			(effects
				(font
					(size 0.7 0.7)
					(thickness 0.15)
				)
				(justify left bottom)
			)
		)
		(pad "1" smd roundrect
			(at -0.48 0 270)
			(size 0.59 0.64)
			(layers "F.Cu" "F.Mask" "F.Paste")
			(roundrect_rratio 0.25)
			(net 417 "GND")
			(pintype "passive")
		)
		(pad "2" smd roundrect
			(at 0.48 0 270)
			(size 0.59 0.64)
			(layers "F.Cu" "F.Mask" "F.Paste")
			(roundrect_rratio 0.25)
			(net 522 "/Supply/1V05_REG")
			(pintype "passive")
		)
	)
	(footprint "antmicro-footprints:R_0402_1005Metric"
		(layer "B.Cu")
		(at 201.5 122.6 180)
		(descr "Resistor SMD 0402")
		(tags "resistor SMD 0402")
		(property "Reference" "R105"
			(at -4.71 -0.98 0)
			(layer "B.SilkS")
			(effects
				(font
					(size 0.7 0.7)
					(thickness 0.15)
				)
				(justify left bottom mirror)
			)
		)
		(property "Value" "R_4k7_0402"
			(at -1.011843 -1.772047 0)
			(layer "B.Fab")
			(hide yes)
			(effects
				(font
					(size 0.7 0.7)
					(thickness 0.15)
				)
				(justify left bottom mirror)
			)
		)
		(property "Datasheet" "https://www.bourns.com/docs/product-datasheets/cr.pdf"
			(at 0 0 180)
			(layer "F.Fab")
			(hide yes)
			(effects
				(font
					(size 1.27 1.27)
					(thickness 0.15)
				)
			)
		)
		(property "Description" "SMD Chip Resistor, 4.7 kohm, ± 1%, 62.5 mW, 0402 [1005 Metric], Thick Film, General Purpose"
			(at 0 0 180)
			(layer "F.Fab")
			(hide yes)
			(effects
				(font
					(size 1.27 1.27)
					(thickness 0.15)
				)
			)
		)
		(property "Author" "Antmicro"
			(at 403 245.2 0)
			(layer "B.Fab")
			(hide yes)
			(effects
				(font
					(size 1 1)
					(thickness 0.15)
				)
				(justify mirror)
			)
		)
		(property "License" "Apache-2.0"
			(at 403 245.2 0)
			(layer "B.Fab")
			(hide yes)
			(effects
				(font
					(size 1 1)
					(thickness 0.15)
				)
				(justify mirror)
			)
		)
		(property "MPN" "CR0402-FX-4701GLF"
			(at 403 245.2 0)
			(layer "B.Fab")
			(hide yes)
			(effects
				(font
					(size 1 1)
					(thickness 0.15)
				)
				(justify mirror)
			)
		)
		(property "Manufacturer" "Bourns"
			(at 403 245.2 0)
			(layer "B.Fab")
			(hide yes)
			(effects
				(font
					(size 1 1)
					(thickness 0.15)
				)
				(justify mirror)
			)
		)
		(property "Public" ""
			(at 403 245.2 0)
			(layer "B.Fab")
			(hide yes)
			(effects
				(font
					(size 1 1)
					(thickness 0.15)
				)
				(justify mirror)
			)
		)
		(property "Tolerance" "1%"
			(at 403 245.2 0)
			(layer "B.Fab")
			(hide yes)
			(effects
				(font
					(size 1 1)
					(thickness 0.15)
				)
				(justify mirror)
			)
		)
		(property "Val" "4k7"
			(at 403 245.2 0)
			(layer "B.Fab")
			(hide yes)
			(effects
				(font
					(size 1 1)
					(thickness 0.15)
				)
				(justify mirror)
			)
		)
		(sheetname "/FPGA MSSIO/")
		(sheetfile "fpga-mssio.kicad_sch")
		(attr smd)
		(fp_rect
			(start -0.925 0.47)
			(end 0.925 -0.47)
			(stroke
				(width 0.05)
				(type default)
			)
			(fill no)
			(layer "B.CrtYd")
		)
		(fp_rect
			(start -0.5 0.25)
			(end 0.5 -0.25)
			(stroke
				(width 0.15)
				(type solid)
			)
			(fill no)
			(layer "B.Fab")
		)
		(fp_text user "License: Apache-2.0"
			(at -0.95 -5.169 0)
			(layer "B.Fab")
			(effects
				(font
					(size 0.7 0.7)
					(thickness 0.15)
				)
				(justify left bottom mirror)
			)
		)
		(fp_text user "${REFERENCE}"
			(at -0.95 -3.168 0)
			(layer "B.Fab")
			(effects
				(font
					(size 0.7 0.7)
					(thickness 0.15)
				)
				(justify left bottom mirror)
			)
		)
		(fp_text user "Author: Antmicro"
			(at -0.95 -4.169 0)
			(layer "B.Fab")
			(effects
				(font
					(size 0.7 0.7)
					(thickness 0.15)
				)
				(justify left bottom mirror)
			)
		)
		(pad "1" smd roundrect
			(at -0.48 0 180)
			(size 0.59 0.64)
			(layers "B.Cu" "B.Mask" "B.Paste")
			(roundrect_rratio 0.25)
			(net 92 "/FPGA MSSIO/SUPPLY.SCL")
			(pintype "passive")
		)
		(pad "2" smd roundrect
			(at 0.48 0 180)
			(size 0.59 0.64)
			(layers "B.Cu" "B.Mask" "B.Paste")
			(roundrect_rratio 0.25)
			(net 649 "VDD")
			(pintype "passive")
		)
	)
	(footprint "antmicro-footprints:SOT-523"
		(layer "B.Cu")
		(at 182.65 118.65 180)
		(property "Reference" "Q10"
			(at -1.05 1.3 0)
			(layer "B.SilkS")
			(effects
				(font
					(size 0.7 0.7)
					(thickness 0.15)
				)
				(justify left bottom mirror)
			)
		)
		(property "Value" "DMG1012T-7"
			(at 0.1 -1.824 0)
			(layer "B.Fab")
			(hide yes)
			(effects
				(font
					(size 0.7 0.7)
					(thickness 0.15)
				)
				(justify left bottom mirror)
			)
		)
		(property "Datasheet" "https://www.diodes.com/assets/Datasheets/ds31783.pdf"
			(at 0 0 0)
			(layer "B.Fab")
			(hide yes)
			(effects
				(font
					(size 1.27 1.27)
					(thickness 0.15)
				)
				(justify mirror)
			)
		)
		(property "Description" "Power MOSFET, N Channel, 20 V, 630 mA, 0.3 ohm, SOT-523, Surface Mount"
			(at 0 0 0)
			(layer "B.Fab")
			(hide yes)
			(effects
				(font
					(size 1.27 1.27)
					(thickness 0.15)
				)
				(justify mirror)
			)
		)
		(property "MPN" "DMG1012T-7"
			(at 0 0 0)
			(unlocked yes)
			(layer "B.Fab")
			(hide yes)
			(effects
				(font
					(size 1 1)
					(thickness 0.15)
				)
				(justify mirror)
			)
		)
		(property "Manufacturer" "Diodes Incorporated"
			(at 0 0 0)
			(unlocked yes)
			(layer "B.Fab")
			(hide yes)
			(effects
				(font
					(size 1 1)
					(thickness 0.15)
				)
				(justify mirror)
			)
		)
		(property "Author" "Antmicro"
			(at 0 0 0)
			(unlocked yes)
			(layer "B.Fab")
			(hide yes)
			(effects
				(font
					(size 1 1)
					(thickness 0.15)
				)
				(justify mirror)
			)
		)
		(property "License" "Apache-2.0"
			(at 0 0 0)
			(unlocked yes)
			(layer "B.Fab")
			(hide yes)
			(effects
				(font
					(size 1 1)
					(thickness 0.15)
				)
				(justify mirror)
			)
		)
		(property "Public" ""
			(at 0 0 0)
			(unlocked yes)
			(layer "B.Fab")
			(hide yes)
			(effects
				(font
					(size 1 1)
					(thickness 0.15)
				)
				(justify mirror)
			)
		)
		(sheetname "/FPGA Config/")
		(sheetfile "fpga-config.kicad_sch")
		(attr smd)
		(fp_line
			(start -0.277 0.551)
			(end -0.277 0.75)
			(stroke
				(width 0.15)
				(type solid)
			)
			(layer "B.SilkS")
		)
		(fp_line
			(start -0.725 0.551)
			(end -0.277 0.551)
			(stroke
				(width 0.15)
				(type solid)
			)
			(layer "B.SilkS")
		)
		(fp_line
			(start -0.927 0.351)
			(end -0.725 0.551)
			(stroke
				(width 0.15)
				(type solid)
			)
			(layer "B.SilkS")
		)
		(fp_line
			(start -0.927 0.051)
			(end -0.927 0.351)
			(stroke
				(width 0.15)
				(type solid)
			)
			(layer "B.SilkS")
		)
		(fp_circle
			(center -0.9652 -0.9652)
			(end -0.9152 -0.9652)
			(stroke
				(width 0.15)
				(type solid)
			)
			(fill yes)
			(layer "B.SilkS")
		)
		(fp_line
			(start 1.1 1.16)
			(end 1.1 -1.15)
			(stroke
				(width 0.05)
				(type solid)
			)
			(layer "B.CrtYd")
		)
		(fp_line
			(start -1.12 1.16)
			(end 1.1 1.16)
			(stroke
				(width 0.05)
				(type solid)
			)
			(layer "B.CrtYd")
		)
		(fp_line
			(start -1.12 1.16)
			(end -1.12 -1.15)
			(stroke
				(width 0.05)
				(type solid)
			)
			(layer "B.CrtYd")
		)
		(fp_line
			(start -1.12 -1.15)
			(end 1.1 -1.15)
			(stroke
				(width 0.05)
				(type solid)
			)
			(layer "B.CrtYd")
		)
		(fp_line
			(start 0.8 0.425)
			(end 0.8 -0.424)
			(stroke
				(width 0.15)
				(type solid)
			)
			(layer "B.Fab")
		)
		(fp_line
			(start 0.8 0.425)
			(end -0.652 0.425)
			(stroke
				(width 0.15)
				(type solid)
			)
			(layer "B.Fab")
		)
		(fp_line
			(start 0.8 -0.424)
			(end -0.802 -0.424)
			(stroke
				(width 0.15)
				(type solid)
			)
			(layer "B.Fab")
		)
		(fp_line
			(start -0.652 0.425)
			(end -0.802 0.276)
			(stroke
				(width 0.15)
				(type solid)
			)
			(layer "B.Fab")
		)
		(fp_line
			(start -0.802 0.276)
			(end -0.802 -0.424)
			(stroke
				(width 0.15)
				(type solid)
			)
			(layer "B.Fab")
		)
		(fp_circle
			(center -0.9652 -0.9652)
			(end -0.9144 -0.9652)
			(stroke
				(width 0.15)
				(type solid)
			)
			(fill no)
			(layer "B.Fab")
		)
		(fp_text user "Author: Antmicro"
			(at -1.12 -6.224 0)
			(layer "B.Fab")
			(effects
				(font
					(size 0.7 0.7)
					(thickness 0.15)
				)
				(justify left bottom mirror)
			)
		)
		(fp_text user "${REFERENCE}"
			(at -1.12 -3.824 0)
			(layer "B.Fab")
			(effects
				(font
					(size 0.7 0.7)
					(thickness 0.15)
				)
				(justify left bottom mirror)
			)
		)
		(fp_text user "License: Apache-2.0"
			(at -1.12 -5.024 0)
			(layer "B.Fab")
			(effects
				(font
					(size 0.7 0.7)
					(thickness 0.15)
				)
				(justify left bottom mirror)
			)
		)
		(pad "1" smd rect
			(at -0.5 -0.65 180)
			(size 0.4 0.51)
			(layers "B.Cu" "B.Mask" "B.Paste")
			(net 230 "~{PG}")
			(pinfunction "G")
			(pintype "input")
		)
		(pad "2" smd rect
			(at 0.498 -0.65 180)
			(size 0.4 0.51)
			(layers "B.Cu" "B.Mask" "B.Paste")
			(net 417 "GND")
			(pinfunction "S")
			(pintype "passive")
		)
		(pad "3" smd rect
			(at 0 0.652 180)
			(size 0.4 0.51)
			(layers "B.Cu" "B.Mask" "B.Paste")
			(net 655 "/FPGA Config/DEVRST_N")
			(pinfunction "D")
			(pintype "passive")
		)
	)
	(footprint "antmicro-footprints:C_0402_1005Metric"
		(layer "B.Cu")
		(at 198.78 123.56)
		(descr "Capacitor SMD 0402")
		(tags "capacitor SMD 0402")
		(property "Reference" "C14"
			(at -0.855 0.115 180)
			(layer "B.SilkS")
			(effects
				(font
					(size 0.7 0.7)
					(thickness 0.15)
				)
				(justify left bottom mirror)
			)
		)
		(property "Value" "C_100n_0402"
			(at -1.022927 -2.155213 180)
			(layer "B.Fab")
			(hide yes)
			(effects
				(font
					(size 0.7 0.7)
					(thickness 0.15)
				)
				(justify left bottom mirror)
			)
		)
		(property "Datasheet" "https://www.murata.com/products/productdetail?partno=GRM155R61H104KE14%23"
			(at 0 0 0)
			(layer "F.Fab")
			(hide yes)
			(effects
				(font
					(size 1.27 1.27)
					(thickness 0.15)
				)
			)
		)
		(property "Description" "SMD Multilayer Ceramic Capacitor, 0.1 µF, 50 V, 0402 [1005 Metric], ± 10%, X5R, GRM Series"
			(at 0 0 0)
			(layer "F.Fab")
			(hide yes)
			(effects
				(font
					(size 1.27 1.27)
					(thickness 0.15)
				)
			)
		)
		(property "Author" "Antmicro"
			(at 0 0 0)
			(layer "B.Fab")
			(hide yes)
			(effects
				(font
					(size 1 1)
					(thickness 0.15)
				)
				(justify mirror)
			)
		)
		(property "Dielectric" "X5R"
			(at 0 0 0)
			(layer "B.Fab")
			(hide yes)
			(effects
				(font
					(size 1 1)
					(thickness 0.15)
				)
				(justify mirror)
			)
		)
		(property "License" "Apache-2.0"
			(at 0 0 0)
			(layer "B.Fab")
			(hide yes)
			(effects
				(font
					(size 1 1)
					(thickness 0.15)
				)
				(justify mirror)
			)
		)
		(property "MPN" "GRM155R61H104KE14D"
			(at 0 0 0)
			(layer "B.Fab")
			(hide yes)
			(effects
				(font
					(size 1 1)
					(thickness 0.15)
				)
				(justify mirror)
			)
		)
		(property "Manufacturer" "Murata"
			(at 0 0 0)
			(layer "B.Fab")
			(hide yes)
			(effects
				(font
					(size 1 1)
					(thickness 0.15)
				)
				(justify mirror)
			)
		)
		(property "Public" ""
			(at 0 0 0)
			(layer "B.Fab")
			(hide yes)
			(effects
				(font
					(size 1 1)
					(thickness 0.15)
				)
				(justify mirror)
			)
		)
		(property "Val" "100n"
			(at 0 0 0)
			(layer "B.Fab")
			(hide yes)
			(effects
				(font
					(size 1 1)
					(thickness 0.15)
				)
				(justify mirror)
			)
		)
		(property "Voltage" "50V"
			(at 0 0 0)
			(layer "B.Fab")
			(hide yes)
			(effects
				(font
					(size 1 1)
					(thickness 0.15)
				)
				(justify mirror)
			)
		)
		(sheetname "/FPGA Supply/")
		(sheetfile "fpga-supply.kicad_sch")
		(attr smd)
		(fp_rect
			(start -0.925 0.47)
			(end 0.925 -0.47)
			(stroke
				(width 0.05)
				(type default)
			)
			(fill no)
			(layer "B.CrtYd")
		)
		(fp_line
			(start -0.494 -0.248)
			(end -0.494 0.25)
			(stroke
				(width 0.15)
				(type solid)
			)
			(layer "B.Fab")
		)
		(fp_line
			(start -0.494 0.25)
			(end 0.504 0.25)
			(stroke
				(width 0.15)
				(type solid)
			)
			(layer "B.Fab")
		)
		(fp_line
			(start 0.504 -0.248)
			(end -0.494 -0.248)
			(stroke
				(width 0.15)
				(type solid)
			)
			(layer "B.Fab")
		)
		(fp_line
			(start 0.504 0.25)
			(end 0.504 -0.248)
			(stroke
				(width 0.15)
				(type solid)
			)
			(layer "B.Fab")
		)
		(fp_text user "Author: Antmicro"
			(at -0.939 -3.399 180)
			(layer "B.Fab")
			(effects
				(font
					(size 0.7 0.7)
					(thickness 0.15)
				)
				(justify left bottom mirror)
			)
		)
		(fp_text user "${REFERENCE}"
			(at -0.939 -4.599 180)
			(layer "B.Fab")
			(effects
				(font
					(size 0.7 0.7)
					(thickness 0.15)
				)
				(justify left bottom mirror)
			)
		)
		(fp_text user "License: Apache-2.0"
			(at -0.939 -5.799 180)
			(layer "B.Fab")
			(effects
				(font
					(size 0.7 0.7)
					(thickness 0.15)
				)
				(justify left bottom mirror)
			)
		)
		(pad "1" smd roundrect
			(at -0.48 0)
			(size 0.59 0.64)
			(layers "B.Cu" "B.Mask" "B.Paste")
			(roundrect_rratio 0.25)
			(net 417 "GND")
			(pintype "passive")
		)
		(pad "2" smd roundrect
			(at 0.48 0)
			(size 0.59 0.64)
			(layers "B.Cu" "B.Mask" "B.Paste")
			(roundrect_rratio 0.25)
			(net 137 "SD_VDD")
			(pintype "passive")
		)
	)
)
